(kicad_pcb
	(version 20260206)
	(generator "pcbnew")
	(generator_version "10.0")
	(general
		(thickness 1.6)
		(legacy_teardrops no)
	)
	(paper "A4")
	(title_block
		(title "01162023_DA0F0TEBIF0_F0T_Expander_BD_F_brd_V02_OCP.brd")
		(comment 1 "Grand Teton / footprints 8372-8380 of 9728")
	)
	(layers
		(0 "F.Cu" signal "TOP")
		(4 "In1.Cu" signal "GND")
		(6 "In2.Cu" signal "VCC")
		(8 "In3.Cu" signal "VCC1")
		(10 "In4.Cu" signal "GND1")
		(12 "In5.Cu" signal "IN1")
		(14 "In6.Cu" signal "GND2")
		(16 "In7.Cu" signal "IN2")
		(18 "In8.Cu" signal "GND3")
		(20 "In9.Cu" signal "IN3")
		(22 "In10.Cu" signal "GND4")
		(24 "In11.Cu" signal "IN4")
		(26 "In12.Cu" signal "GND5")
		(28 "In13.Cu" signal "IN5")
		(30 "In14.Cu" signal "GND6")
		(32 "In15.Cu" signal "IN6")
		(34 "In16.Cu" signal "GND7")
		(2 "B.Cu" signal "BOTTOM")
		(9 "F.Adhes" user "F.Adhesive")
		(11 "B.Adhes" user "B.Adhesive")
		(13 "F.Paste" user "Package Geometry/Pastemask Top")
		(15 "B.Paste" user "Package Geometry/Pastemask Bottom")
		(5 "F.SilkS" user "Ref Des/Silkscreen Top")
		(7 "B.SilkS" user "Ref Des/Silkscreen Bottom")
		(1 "F.Mask" user "Board Geometry/Soldermask Top")
		(3 "B.Mask" user "Board Geometry/Soldermask Bottom")
		(17 "Dwgs.User" user "User.Drawings")
		(19 "Cmts.User" user "User.Comments")
		(21 "Eco1.User" user "User.Eco1")
		(23 "Eco2.User" user "User.Eco2")
		(25 "Edge.Cuts" user "Board Geometry/Outline")
		(27 "Margin" user)
		(31 "F.CrtYd" user "Package Geometry/Place Bound Top")
		(29 "B.CrtYd" user "Package Geometry/Place Bound Bottom")
		(35 "F.Fab" user "Ref Des/Assembly Top")
		(33 "B.Fab" user "Ref Des/Assembly Bottom")
	)
	(footprint ""
		(layer "B.Cu")
		(at 54.945534 -296.37482)
		(property "Reference" "C1113"
			(at 0 0 0)
			(layer "B.SilkS")
			(hide yes)
			(effects
				(font
					(size 1.27 1.27)
				)
				(justify mirror)
			)
		)
		(property "Value" ""
			(at 0 0 0)
			(layer "B.Fab")
			(effects
				(font
					(size 1.27 1.27)
				)
				(justify mirror)
			)
		)
		(duplicate_pad_numbers_are_jumpers no)
		(fp_line
			(start -0.299974 -0.150114)
			(end -0.299974 0.150114)
			(stroke
				(width 0.1)
				(type default)
			)
			(layer "B.Fab")
		)
		(fp_line
			(start -0.299974 0.150114)
			(end 0.299974 0.150114)
			(stroke
				(width 0.1)
				(type default)
			)
			(layer "B.Fab")
		)
		(fp_line
			(start 0.299974 -0.150114)
			(end -0.299974 -0.150114)
			(stroke
				(width 0.1)
				(type default)
			)
			(layer "B.Fab")
		)
		(fp_line
			(start 0.299974 0.150114)
			(end 0.299974 -0.150114)
			(stroke
				(width 0.1)
				(type default)
			)
			(layer "B.Fab")
		)
		(pad "1" smd rect
			(at 0.2667 0 180)
			(size 0.3048 0.381)
			(layers "B.Cu" "B.Mask" "B.Paste")
			(net "P0V8_PEX0")
		)
		(pad "2" smd rect
			(at -0.2667 0 180)
			(size 0.3048 0.381)
			(layers "B.Cu" "B.Mask" "B.Paste")
			(net "GND")
		)
	)
	(footprint ""
		(layer "B.Cu")
		(at 281.755342 -150.9776)
		(property "Reference" "R224"
			(at 0 0 0)
			(layer "B.SilkS")
			(hide yes)
			(effects
				(font
					(size 1.27 1.27)
				)
				(justify mirror)
			)
		)
		(property "Value" ""
			(at 0 0 0)
			(layer "B.Fab")
			(effects
				(font
					(size 1.27 1.27)
				)
				(justify mirror)
			)
		)
		(duplicate_pad_numbers_are_jumpers no)
		(fp_line
			(start -0.7874 -0.4064)
			(end -0.7874 0.4064)
			(stroke
				(width 0.1524)
				(type default)
			)
			(layer "B.SilkS")
		)
		(fp_line
			(start -0.7874 0.4064)
			(end 0.7874 0.4064)
			(stroke
				(width 0.1524)
				(type default)
			)
			(layer "B.SilkS")
		)
		(fp_line
			(start 0.7874 -0.4064)
			(end -0.7874 -0.4064)
			(stroke
				(width 0.1524)
				(type default)
			)
			(layer "B.SilkS")
		)
		(fp_line
			(start 0.7874 0.4064)
			(end 0.7874 -0.4064)
			(stroke
				(width 0.1524)
				(type default)
			)
			(layer "B.SilkS")
		)
		(fp_line
			(start -0.67945 -0.3048)
			(end -0.67945 0.3048)
			(stroke
				(width 0.1)
				(type default)
			)
			(layer "B.Fab")
		)
		(fp_line
			(start -0.67945 0.3048)
			(end -0.120396 0.3048)
			(stroke
				(width 0.1)
				(type default)
			)
			(layer "B.Fab")
		)
		(fp_line
			(start -0.12065 -0.3048)
			(end -0.67945 -0.3048)
			(stroke
				(width 0.1)
				(type default)
			)
			(layer "B.Fab")
		)
		(fp_line
			(start -0.12065 -0.2794)
			(end -0.12065 -0.3048)
			(stroke
				(width 0.1)
				(type default)
			)
			(layer "B.Fab")
		)
		(fp_line
			(start -0.120396 0.2794)
			(end 0.12065 0.2794)
			(stroke
				(width 0.1)
				(type default)
			)
			(layer "B.Fab")
		)
		(fp_line
			(start -0.120396 0.3048)
			(end -0.120396 0.2794)
			(stroke
				(width 0.1)
				(type default)
			)
			(layer "B.Fab")
		)
		(fp_line
			(start 0.12065 -0.305054)
			(end 0.12065 -0.2794)
			(stroke
				(width 0.1)
				(type default)
			)
			(layer "B.Fab")
		)
		(fp_line
			(start 0.12065 -0.2794)
			(end -0.12065 -0.2794)
			(stroke
				(width 0.1)
				(type default)
			)
			(layer "B.Fab")
		)
		(fp_line
			(start 0.12065 0.2794)
			(end 0.12065 0.3048)
			(stroke
				(width 0.1)
				(type default)
			)
			(layer "B.Fab")
		)
		(fp_line
			(start 0.12065 0.3048)
			(end 0.67945 0.3048)
			(stroke
				(width 0.1)
				(type default)
			)
			(layer "B.Fab")
		)
		(fp_line
			(start 0.67945 -0.305054)
			(end 0.12065 -0.305054)
			(stroke
				(width 0.1)
				(type default)
			)
			(layer "B.Fab")
		)
		(fp_line
			(start 0.67945 0.3048)
			(end 0.67945 -0.305054)
			(stroke
				(width 0.1)
				(type default)
			)
			(layer "B.Fab")
		)
		(pad "1" smd circle
			(at 0.40005 0 180)
			(size 0 0)
			(layers "B.Cu" "B.Mask" "B.Paste")
			(net "CLK_50M_NIC4_RBT_REF")
		)
		(pad "2" smd circle
			(at -0.40005 0 180)
			(size 0 0)
			(layers "B.Cu" "B.Mask" "B.Paste")
			(net "GND")
		)
	)
	(footprint ""
		(layer "B.Cu")
		(at 193.641726 -97.005648 180)
		(property "Reference" "R165"
			(at 0 0 0)
			(layer "B.SilkS")
			(hide yes)
			(effects
				(font
					(size 1.27 1.27)
				)
				(justify mirror)
			)
		)
		(property "Value" ""
			(at 0 0 0)
			(layer "B.Fab")
			(effects
				(font
					(size 1.27 1.27)
				)
				(justify mirror)
			)
		)
		(duplicate_pad_numbers_are_jumpers no)
		(fp_line
			(start 0.7874 0.4064)
			(end 0.7874 -0.4064)
			(stroke
				(width 0.1524)
				(type default)
			)
			(layer "B.SilkS")
		)
		(fp_line
			(start 0.7874 -0.4064)
			(end -0.7874 -0.4064)
			(stroke
				(width 0.1524)
				(type default)
			)
			(layer "B.SilkS")
		)
		(fp_line
			(start -0.7874 0.4064)
			(end 0.7874 0.4064)
			(stroke
				(width 0.1524)
				(type default)
			)
			(layer "B.SilkS")
		)
		(fp_line
			(start -0.7874 -0.4064)
			(end -0.7874 0.4064)
			(stroke
				(width 0.1524)
				(type default)
			)
			(layer "B.SilkS")
		)
		(fp_line
			(start 0.67945 0.3048)
			(end 0.67945 -0.305054)
			(stroke
				(width 0.1)
				(type default)
			)
			(layer "B.Fab")
		)
		(fp_line
			(start 0.67945 -0.305054)
			(end 0.12065 -0.305054)
			(stroke
				(width 0.1)
				(type default)
			)
			(layer "B.Fab")
		)
		(fp_line
			(start 0.12065 0.3048)
			(end 0.67945 0.3048)
			(stroke
				(width 0.1)
				(type default)
			)
			(layer "B.Fab")
		)
		(fp_line
			(start 0.12065 0.2794)
			(end 0.12065 0.3048)
			(stroke
				(width 0.1)
				(type default)
			)
			(layer "B.Fab")
		)
		(fp_line
			(start 0.12065 -0.2794)
			(end -0.12065 -0.2794)
			(stroke
				(width 0.1)
				(type default)
			)
			(layer "B.Fab")
		)
		(fp_line
			(start 0.12065 -0.305054)
			(end 0.12065 -0.2794)
			(stroke
				(width 0.1)
				(type default)
			)
			(layer "B.Fab")
		)
		(fp_line
			(start -0.120396 0.3048)
			(end -0.120396 0.2794)
			(stroke
				(width 0.1)
				(type default)
			)
			(layer "B.Fab")
		)
		(fp_line
			(start -0.120396 0.2794)
			(end 0.12065 0.2794)
			(stroke
				(width 0.1)
				(type default)
			)
			(layer "B.Fab")
		)
		(fp_line
			(start -0.12065 -0.2794)
			(end -0.12065 -0.3048)
			(stroke
				(width 0.1)
				(type default)
			)
			(layer "B.Fab")
		)
		(fp_line
			(start -0.12065 -0.3048)
			(end -0.67945 -0.3048)
			(stroke
				(width 0.1)
				(type default)
			)
			(layer "B.Fab")
		)
		(fp_line
			(start -0.67945 0.3048)
			(end -0.120396 0.3048)
			(stroke
				(width 0.1)
				(type default)
			)
			(layer "B.Fab")
		)
		(fp_line
			(start -0.67945 -0.3048)
			(end -0.67945 0.3048)
			(stroke
				(width 0.1)
				(type default)
			)
			(layer "B.Fab")
		)
		(pad "1" smd circle
			(at 0.40005 0)
			(size 0 0)
			(layers "B.Cu" "B.Mask" "B.Paste")
			(net "NIC3_DATA_IN")
		)
		(pad "2" smd circle
			(at -0.40005 0)
			(size 0 0)
			(layers "B.Cu" "B.Mask" "B.Paste")
			(net "P3V3_NIC3")
		)
	)
	(footprint ""
		(layer "B.Cu")
		(at 303.249838 -296.37482 180)
		(property "Reference" "C3285"
			(at 0 0 0)
			(layer "B.SilkS")
			(hide yes)
			(effects
				(font
					(size 1.27 1.27)
				)
				(justify mirror)
			)
		)
		(property "Value" ""
			(at 0 0 0)
			(layer "B.Fab")
			(effects
				(font
					(size 1.27 1.27)
				)
				(justify mirror)
			)
		)
		(duplicate_pad_numbers_are_jumpers no)
		(fp_line
			(start 0.299974 0.150114)
			(end 0.299974 -0.150114)
			(stroke
				(width 0.1)
				(type default)
			)
			(layer "B.Fab")
		)
		(fp_line
			(start 0.299974 -0.150114)
			(end -0.299974 -0.150114)
			(stroke
				(width 0.1)
				(type default)
			)
			(layer "B.Fab")
		)
		(fp_line
			(start -0.299974 0.150114)
			(end 0.299974 0.150114)
			(stroke
				(width 0.1)
				(type default)
			)
			(layer "B.Fab")
		)
		(fp_line
			(start -0.299974 -0.150114)
			(end -0.299974 0.150114)
			(stroke
				(width 0.1)
				(type default)
			)
			(layer "B.Fab")
		)
		(pad "1" smd rect
			(at 0.2667 0)
			(size 0.3048 0.381)
			(layers "B.Cu" "B.Mask" "B.Paste")
			(net "P1V25_PEX2")
		)
		(pad "2" smd rect
			(at -0.2667 0)
			(size 0.3048 0.381)
			(layers "B.Cu" "B.Mask" "B.Paste")
			(net "GND")
		)
	)
	(footprint ""
		(layer "B.Cu")
		(at 70.099936 -288.774886 180)
		(property "Reference" "C3002"
			(at 0 0 0)
			(layer "B.SilkS")
			(hide yes)
			(effects
				(font
					(size 1.27 1.27)
				)
				(justify mirror)
			)
		)
		(property "Value" ""
			(at 0 0 0)
			(layer "B.Fab")
			(effects
				(font
					(size 1.27 1.27)
				)
				(justify mirror)
			)
		)
		(duplicate_pad_numbers_are_jumpers no)
		(fp_line
			(start 0.299974 0.150114)
			(end 0.299974 -0.150114)
			(stroke
				(width 0.1)
				(type default)
			)
			(layer "B.Fab")
		)
		(fp_line
			(start 0.299974 -0.150114)
			(end -0.299974 -0.150114)
			(stroke
				(width 0.1)
				(type default)
			)
			(layer "B.Fab")
		)
		(fp_line
			(start -0.299974 0.150114)
			(end 0.299974 0.150114)
			(stroke
				(width 0.1)
				(type default)
			)
			(layer "B.Fab")
		)
		(fp_line
			(start -0.299974 -0.150114)
			(end -0.299974 0.150114)
			(stroke
				(width 0.1)
				(type default)
			)
			(layer "B.Fab")
		)
		(pad "1" smd rect
			(at 0.2667 0)
			(size 0.3048 0.381)
			(layers "B.Cu" "B.Mask" "B.Paste")
			(net "P1V8_PEX")
		)
		(pad "2" smd rect
			(at -0.2667 0)
			(size 0.3048 0.381)
			(layers "B.Cu" "B.Mask" "B.Paste")
			(net "GND")
		)
	)
	(footprint ""
		(layer "B.Cu")
		(at 286.149796 -292.099746 90)
		(property "Reference" "C1744"
			(at 0 0 90)
			(layer "B.SilkS")
			(hide yes)
			(effects
				(font
					(size 1.27 1.27)
				)
				(justify mirror)
			)
		)
		(property "Value" ""
			(at 0 0 90)
			(layer "B.Fab")
			(effects
				(font
					(size 1.27 1.27)
				)
				(justify mirror)
			)
		)
		(duplicate_pad_numbers_are_jumpers no)
		(fp_line
			(start 0.299974 -0.150114)
			(end -0.299974 -0.150114)
			(stroke
				(width 0.1)
				(type default)
			)
			(layer "B.Fab")
		)
		(fp_line
			(start -0.299974 -0.150114)
			(end -0.299974 0.150114)
			(stroke
				(width 0.1)
				(type default)
			)
			(layer "B.Fab")
		)
		(fp_line
			(start 0.299974 0.150114)
			(end 0.299974 -0.150114)
			(stroke
				(width 0.1)
				(type default)
			)
			(layer "B.Fab")
		)
		(fp_line
			(start -0.299974 0.150114)
			(end 0.299974 0.150114)
			(stroke
				(width 0.1)
				(type default)
			)
			(layer "B.Fab")
		)
		(pad "1" smd rect
			(at 0.2667 0 270)
			(size 0.3048 0.381)
			(layers "B.Cu" "B.Mask" "B.Paste")
			(net "P0V8_SERDES_VDDA_PEX2")
		)
		(pad "2" smd rect
			(at -0.2667 0 270)
			(size 0.3048 0.381)
			(layers "B.Cu" "B.Mask" "B.Paste")
			(net "GND")
		)
	)
	(footprint ""
		(layer "B.Cu")
		(at 302.552354 -236.736636 90)
		(property "Reference" "R1859"
			(at 0 0 90)
			(layer "B.SilkS")
			(hide yes)
			(effects
				(font
					(size 1.27 1.27)
				)
				(justify mirror)
			)
		)
		(property "Value" ""
			(at 0 0 90)
			(layer "B.Fab")
			(effects
				(font
					(size 1.27 1.27)
				)
				(justify mirror)
			)
		)
		(duplicate_pad_numbers_are_jumpers no)
		(fp_line
			(start 0.7874 -0.4064)
			(end -0.7874 -0.4064)
			(stroke
				(width 0.1524)
				(type default)
			)
			(layer "B.SilkS")
		)
		(fp_line
			(start -0.7874 -0.4064)
			(end -0.7874 0.4064)
			(stroke
				(width 0.1524)
				(type default)
			)
			(layer "B.SilkS")
		)
		(fp_line
			(start 0.7874 0.4064)
			(end 0.7874 -0.4064)
			(stroke
				(width 0.1524)
				(type default)
			)
			(layer "B.SilkS")
		)
		(fp_line
			(start -0.7874 0.4064)
			(end 0.7874 0.4064)
			(stroke
				(width 0.1524)
				(type default)
			)
			(layer "B.SilkS")
		)
		(fp_line
			(start 0.67945 -0.305054)
			(end 0.12065 -0.305054)
			(stroke
				(width 0.1)
				(type default)
			)
			(layer "B.Fab")
		)
		(fp_line
			(start 0.12065 -0.305054)
			(end 0.12065 -0.2794)
			(stroke
				(width 0.1)
				(type default)
			)
			(layer "B.Fab")
		)
		(fp_line
			(start -0.12065 -0.3048)
			(end -0.67945 -0.3048)
			(stroke
				(width 0.1)
				(type default)
			)
			(layer "B.Fab")
		)
		(fp_line
			(start -0.67945 -0.3048)
			(end -0.67945 0.3048)
			(stroke
				(width 0.1)
				(type default)
			)
			(layer "B.Fab")
		)
		(fp_line
			(start 0.12065 -0.2794)
			(end -0.12065 -0.2794)
			(stroke
				(width 0.1)
				(type default)
			)
			(layer "B.Fab")
		)
		(fp_line
			(start -0.12065 -0.2794)
			(end -0.12065 -0.3048)
			(stroke
				(width 0.1)
				(type default)
			)
			(layer "B.Fab")
		)
		(fp_line
			(start 0.12065 0.2794)
			(end 0.12065 0.3048)
			(stroke
				(width 0.1)
				(type default)
			)
			(layer "B.Fab")
		)
		(fp_line
			(start -0.120396 0.2794)
			(end 0.12065 0.2794)
			(stroke
				(width 0.1)
				(type default)
			)
			(layer "B.Fab")
		)
		(fp_line
			(start 0.67945 0.3048)
			(end 0.67945 -0.305054)
			(stroke
				(width 0.1)
				(type default)
			)
			(layer "B.Fab")
		)
		(fp_line
			(start 0.12065 0.3048)
			(end 0.67945 0.3048)
			(stroke
				(width 0.1)
				(type default)
			)
			(layer "B.Fab")
		)
		(fp_line
			(start -0.120396 0.3048)
			(end -0.120396 0.2794)
			(stroke
				(width 0.1)
				(type default)
			)
			(layer "B.Fab")
		)
		(fp_line
			(start -0.67945 0.3048)
			(end -0.120396 0.3048)
			(stroke
				(width 0.1)
				(type default)
			)
			(layer "B.Fab")
		)
		(pad "1" smd circle
			(at 0.40005 0 270)
			(size 0 0)
			(layers "B.Cu" "B.Mask" "B.Paste")
			(net "P3V3_AUX")
		)
		(pad "2" smd circle
			(at -0.40005 0 270)
			(size 0 0)
			(layers "B.Cu" "B.Mask" "B.Paste")
			(net "RST_GPU_PERST_1_N")
		)
	)
	(footprint ""
		(layer "B.Cu")
		(at 221.257114 -211.591398)
		(property "Reference" "C2010"
			(at 0 0 0)
			(layer "B.SilkS")
			(hide yes)
			(effects
				(font
					(size 1.27 1.27)
				)
				(justify mirror)
			)
		)
		(property "Value" ""
			(at 0 0 0)
			(layer "B.Fab")
			(effects
				(font
					(size 1.27 1.27)
				)
				(justify mirror)
			)
		)
		(duplicate_pad_numbers_are_jumpers no)
		(fp_line
			(start -1.2954 -0.5842)
			(end -1.2954 0.5842)
			(stroke
				(width 0.1524)
				(type default)
			)
			(layer "B.SilkS")
		)
		(fp_line
			(start -1.2954 0.5842)
			(end 1.2954 0.5842)
			(stroke
				(width 0.1524)
				(type default)
			)
			(layer "B.SilkS")
		)
		(fp_line
			(start 1.2954 -0.5842)
			(end -1.2954 -0.5842)
			(stroke
				(width 0.1524)
				(type default)
			)
			(layer "B.SilkS")
		)
		(fp_line
			(start 1.2954 0.5842)
			(end 1.2954 -0.5842)
			(stroke
				(width 0.1524)
				(type default)
			)
			(layer "B.SilkS")
		)
		(fp_line
			(start -1.1938 -0.4064)
			(end -1.1938 0.4064)
			(stroke
				(width 0.1)
				(type default)
			)
			(layer "B.Fab")
		)
		(fp_line
			(start -1.1938 0.4064)
			(end -0.8636 0.4064)
			(stroke
				(width 0.1)
				(type default)
			)
			(layer "B.Fab")
		)
		(fp_line
			(start -0.8636 -0.4572)
			(end -0.8636 -0.4064)
			(stroke
				(width 0.1)
				(type default)
			)
			(layer "B.Fab")
		)
		(fp_line
			(start -0.8636 -0.4064)
			(end -1.1938 -0.4064)
			(stroke
				(width 0.1)
				(type default)
			)
			(layer "B.Fab")
		)
		(fp_line
			(start -0.8636 0.4064)
			(end -0.8636 0.4572)
			(stroke
				(width 0.1)
				(type default)
			)
			(layer "B.Fab")
		)
		(fp_line
			(start -0.8636 0.4572)
			(end 0.8636 0.4572)
			(stroke
				(width 0.1)
				(type default)
			)
			(layer "B.Fab")
		)
		(fp_line
			(start 0.8636 -0.4572)
			(end -0.8636 -0.4572)
			(stroke
				(width 0.1)
				(type default)
			)
			(layer "B.Fab")
		)
		(fp_line
			(start 0.8636 -0.4064)
			(end 0.8636 -0.4572)
			(stroke
				(width 0.1)
				(type default)
			)
			(layer "B.Fab")
		)
		(fp_line
			(start 0.8636 0.4064)
			(end 1.1938 0.4064)
			(stroke
				(width 0.1)
				(type default)
			)
			(layer "B.Fab")
		)
		(fp_line
			(start 0.8636 0.4572)
			(end 0.8636 0.4064)
			(stroke
				(width 0.1)
				(type default)
			)
			(layer "B.Fab")
		)
		(fp_line
			(start 1.1938 -0.4064)
			(end 0.8636 -0.4064)
			(stroke
				(width 0.1)
				(type default)
			)
			(layer "B.Fab")
		)
		(fp_line
			(start 1.1938 0.4064)
			(end 1.1938 -0.4064)
			(stroke
				(width 0.1)
				(type default)
			)
			(layer "B.Fab")
		)
		(pad "1" smd rect
			(at 0.7366 0 270)
			(size 0.7112 0.8128)
			(layers "B.Cu" "B.Mask" "B.Paste")
			(net "P3V3_AUX")
		)
		(pad "2" smd rect
			(at -0.7366 0 270)
			(size 0.7112 0.8128)
			(layers "B.Cu" "B.Mask" "B.Paste")
			(net "GND")
		)
	)
	(footprint ""
		(layer "B.Cu")
		(at 402.249894 -301.599854 -90)
		(property "Reference" "C1969"
			(at 0 0 90)
			(layer "B.SilkS")
			(hide yes)
			(effects
				(font
					(size 1.27 1.27)
				)
				(justify mirror)
			)
		)
		(property "Value" ""
			(at 0 0 90)
			(layer "B.Fab")
			(effects
				(font
					(size 1.27 1.27)
				)
				(justify mirror)
			)
		)
		(duplicate_pad_numbers_are_jumpers no)
		(fp_line
			(start -0.299974 0.150114)
			(end 0.299974 0.150114)
			(stroke
				(width 0.1)
				(type default)
			)
			(layer "B.Fab")
		)
		(fp_line
			(start 0.299974 0.150114)
			(end 0.299974 -0.150114)
			(stroke
				(width 0.1)
				(type default)
			)
			(layer "B.Fab")
		)
		(fp_line
			(start -0.299974 -0.150114)
			(end -0.299974 0.150114)
			(stroke
				(width 0.1)
				(type default)
			)
			(layer "B.Fab")
		)
		(fp_line
			(start 0.299974 -0.150114)
			(end -0.299974 -0.150114)
			(stroke
				(width 0.1)
				(type default)
			)
			(layer "B.Fab")
		)
		(pad "1" smd rect
			(at 0.2667 0 90)
			(size 0.3048 0.381)
			(layers "B.Cu" "B.Mask" "B.Paste")
			(net "P0V8_SERDES_VDDA_PEX3")
		)
		(pad "2" smd rect
			(at -0.2667 0 90)
			(size 0.3048 0.381)
			(layers "B.Cu" "B.Mask" "B.Paste")
			(net "GND")
		)
	)
)
